(kicad_pcb
	(version 20260206)
	(generator "pcbnew")
	(generator_version "10.0")
	(general
		(thickness 1.6)
		(legacy_teardrops no)
	)
	(paper "A4")
	(title_block
		(title "01162023_DA0F0TEBIF0_F0T_Expander_BD_F_brd_V02_OCP.brd")
		(comment 1 "Grand Teton / footprints 5205-5211 of 9728")
	)
	(layers
		(0 "F.Cu" signal "TOP")
		(4 "In1.Cu" signal "GND")
		(6 "In2.Cu" signal "VCC")
		(8 "In3.Cu" signal "VCC1")
		(10 "In4.Cu" signal "GND1")
		(12 "In5.Cu" signal "IN1")
		(14 "In6.Cu" signal "GND2")
		(16 "In7.Cu" signal "IN2")
		(18 "In8.Cu" signal "GND3")
		(20 "In9.Cu" signal "IN3")
		(22 "In10.Cu" signal "GND4")
		(24 "In11.Cu" signal "IN4")
		(26 "In12.Cu" signal "GND5")
		(28 "In13.Cu" signal "IN5")
		(30 "In14.Cu" signal "GND6")
		(32 "In15.Cu" signal "IN6")
		(34 "In16.Cu" signal "GND7")
		(2 "B.Cu" signal "BOTTOM")
		(9 "F.Adhes" user "F.Adhesive")
		(11 "B.Adhes" user "B.Adhesive")
		(13 "F.Paste" user "Package Geometry/Pastemask Top")
		(15 "B.Paste" user "Package Geometry/Pastemask Bottom")
		(5 "F.SilkS" user "Ref Des/Silkscreen Top")
		(7 "B.SilkS" user "Ref Des/Silkscreen Bottom")
		(1 "F.Mask" user "Board Geometry/Soldermask Top")
		(3 "B.Mask" user "Board Geometry/Soldermask Bottom")
		(17 "Dwgs.User" user "User.Drawings")
		(19 "Cmts.User" user "User.Comments")
		(21 "Eco1.User" user "User.Eco1")
		(23 "Eco2.User" user "User.Eco2")
		(25 "Edge.Cuts" user "Board Geometry/Outline")
		(27 "Margin" user)
		(31 "F.CrtYd" user "Package Geometry/Place Bound Top")
		(29 "B.CrtYd" user "Package Geometry/Place Bound Bottom")
		(35 "F.Fab" user "Ref Des/Assembly Top")
		(33 "B.Fab" user "Ref Des/Assembly Bottom")
	)
	(footprint ""
		(layer "F.Cu")
		(at 148.21916 -59.574684 90)
		(property "Reference" "PC505"
			(at 0 0 90)
			(layer "F.SilkS")
			(hide yes)
			(effects
				(font
					(size 1.27 1.27)
				)
			)
		)
		(property "Value" ""
			(at 0 0 90)
			(layer "F.Fab")
			(effects
				(font
					(size 1.27 1.27)
				)
			)
		)
		(duplicate_pad_numbers_are_jumpers no)
		(fp_line
			(start 0.7874 -0.4064)
			(end 0.7874 0.4064)
			(stroke
				(width 0.1524)
				(type default)
			)
			(layer "F.SilkS")
		)
		(fp_line
			(start -0.7874 -0.4064)
			(end 0.7874 -0.4064)
			(stroke
				(width 0.1524)
				(type default)
			)
			(layer "F.SilkS")
		)
		(fp_line
			(start 0.7874 0.4064)
			(end -0.7874 0.4064)
			(stroke
				(width 0.1524)
				(type default)
			)
			(layer "F.SilkS")
		)
		(fp_line
			(start -0.7874 0.4064)
			(end -0.7874 -0.4064)
			(stroke
				(width 0.1524)
				(type default)
			)
			(layer "F.SilkS")
		)
		(fp_line
			(start -0.12065 -0.305054)
			(end -0.12065 -0.2794)
			(stroke
				(width 0.1)
				(type default)
			)
			(layer "F.Fab")
		)
		(fp_line
			(start -0.67945 -0.305054)
			(end -0.12065 -0.305054)
			(stroke
				(width 0.1)
				(type default)
			)
			(layer "F.Fab")
		)
		(fp_line
			(start 0.67945 -0.3048)
			(end 0.67945 0.3048)
			(stroke
				(width 0.1)
				(type default)
			)
			(layer "F.Fab")
		)
		(fp_line
			(start 0.12065 -0.3048)
			(end 0.67945 -0.3048)
			(stroke
				(width 0.1)
				(type default)
			)
			(layer "F.Fab")
		)
		(fp_line
			(start 0.12065 -0.2794)
			(end 0.12065 -0.3048)
			(stroke
				(width 0.1)
				(type default)
			)
			(layer "F.Fab")
		)
		(fp_line
			(start -0.12065 -0.2794)
			(end 0.12065 -0.2794)
			(stroke
				(width 0.1)
				(type default)
			)
			(layer "F.Fab")
		)
		(fp_line
			(start 0.120396 0.2794)
			(end -0.12065 0.2794)
			(stroke
				(width 0.1)
				(type default)
			)
			(layer "F.Fab")
		)
		(fp_line
			(start -0.12065 0.2794)
			(end -0.12065 0.3048)
			(stroke
				(width 0.1)
				(type default)
			)
			(layer "F.Fab")
		)
		(fp_line
			(start 0.67945 0.3048)
			(end 0.120396 0.3048)
			(stroke
				(width 0.1)
				(type default)
			)
			(layer "F.Fab")
		)
		(fp_line
			(start 0.120396 0.3048)
			(end 0.120396 0.2794)
			(stroke
				(width 0.1)
				(type default)
			)
			(layer "F.Fab")
		)
		(fp_line
			(start -0.12065 0.3048)
			(end -0.67945 0.3048)
			(stroke
				(width 0.1)
				(type default)
			)
			(layer "F.Fab")
		)
		(fp_line
			(start -0.67945 0.3048)
			(end -0.67945 -0.305054)
			(stroke
				(width 0.1)
				(type default)
			)
			(layer "F.Fab")
		)
		(pad "1" smd circle
			(at -0.40005 0 90)
			(size 0 0)
			(layers "F.Cu" "F.Mask" "F.Paste")
			(net "P5V_AUX")
		)
		(pad "2" smd circle
			(at 0.40005 0 90)
			(size 0 0)
			(layers "F.Cu" "F.Mask" "F.Paste")
			(net "GND")
		)
	)
	(footprint ""
		(layer "F.Cu")
		(at 423.95648 -17.419574 180)
		(property "Reference" "R1730"
			(at 0 0 180)
			(layer "F.SilkS")
			(hide yes)
			(effects
				(font
					(size 1.27 1.27)
				)
			)
		)
		(property "Value" ""
			(at 0 0 180)
			(layer "F.Fab")
			(effects
				(font
					(size 1.27 1.27)
				)
			)
		)
		(duplicate_pad_numbers_are_jumpers no)
		(fp_line
			(start 0.7874 0.4064)
			(end -0.7874 0.4064)
			(stroke
				(width 0.1524)
				(type default)
			)
			(layer "F.SilkS")
		)
		(fp_line
			(start 0.7874 -0.4064)
			(end 0.7874 0.4064)
			(stroke
				(width 0.1524)
				(type default)
			)
			(layer "F.SilkS")
		)
		(fp_line
			(start -0.7874 0.4064)
			(end -0.7874 -0.4064)
			(stroke
				(width 0.1524)
				(type default)
			)
			(layer "F.SilkS")
		)
		(fp_line
			(start -0.7874 -0.4064)
			(end 0.7874 -0.4064)
			(stroke
				(width 0.1524)
				(type default)
			)
			(layer "F.SilkS")
		)
		(fp_line
			(start 0.67945 0.3048)
			(end 0.120396 0.3048)
			(stroke
				(width 0.1)
				(type default)
			)
			(layer "F.Fab")
		)
		(fp_line
			(start 0.67945 -0.3048)
			(end 0.67945 0.3048)
			(stroke
				(width 0.1)
				(type default)
			)
			(layer "F.Fab")
		)
		(fp_line
			(start 0.12065 -0.2794)
			(end 0.12065 -0.3048)
			(stroke
				(width 0.1)
				(type default)
			)
			(layer "F.Fab")
		)
		(fp_line
			(start 0.12065 -0.3048)
			(end 0.67945 -0.3048)
			(stroke
				(width 0.1)
				(type default)
			)
			(layer "F.Fab")
		)
		(fp_line
			(start 0.120396 0.3048)
			(end 0.120396 0.2794)
			(stroke
				(width 0.1)
				(type default)
			)
			(layer "F.Fab")
		)
		(fp_line
			(start 0.120396 0.2794)
			(end -0.12065 0.2794)
			(stroke
				(width 0.1)
				(type default)
			)
			(layer "F.Fab")
		)
		(fp_line
			(start -0.12065 0.3048)
			(end -0.67945 0.3048)
			(stroke
				(width 0.1)
				(type default)
			)
			(layer "F.Fab")
		)
		(fp_line
			(start -0.12065 0.2794)
			(end -0.12065 0.3048)
			(stroke
				(width 0.1)
				(type default)
			)
			(layer "F.Fab")
		)
		(fp_line
			(start -0.12065 -0.2794)
			(end 0.12065 -0.2794)
			(stroke
				(width 0.1)
				(type default)
			)
			(layer "F.Fab")
		)
		(fp_line
			(start -0.12065 -0.305054)
			(end -0.12065 -0.2794)
			(stroke
				(width 0.1)
				(type default)
			)
			(layer "F.Fab")
		)
		(fp_line
			(start -0.67945 0.3048)
			(end -0.67945 -0.305054)
			(stroke
				(width 0.1)
				(type default)
			)
			(layer "F.Fab")
		)
		(fp_line
			(start -0.67945 -0.305054)
			(end -0.12065 -0.305054)
			(stroke
				(width 0.1)
				(type default)
			)
			(layer "F.Fab")
		)
		(pad "1" smd circle
			(at -0.40005 0 180)
			(size 0 0)
			(layers "F.Cu" "F.Mask" "F.Paste")
			(net "P3V3_SSD14")
		)
		(pad "2" smd circle
			(at 0.40005 0 180)
			(size 0 0)
			(layers "F.Cu" "F.Mask" "F.Paste")
			(net "SMB_ISO_SSD14_SCL")
		)
	)
	(footprint ""
		(layer "F.Cu")
		(at 186.738768 -22.867366 90)
		(property "Reference" "C3915"
			(at 0 0 90)
			(layer "F.SilkS")
			(hide yes)
			(effects
				(font
					(size 1.27 1.27)
				)
			)
		)
		(property "Value" ""
			(at 0 0 90)
			(layer "F.Fab")
			(effects
				(font
					(size 1.27 1.27)
				)
			)
		)
		(duplicate_pad_numbers_are_jumpers no)
		(fp_line
			(start 0.7874 -0.4064)
			(end 0.7874 0.4064)
			(stroke
				(width 0.1524)
				(type default)
			)
			(layer "F.SilkS")
		)
		(fp_line
			(start -0.7874 -0.4064)
			(end 0.7874 -0.4064)
			(stroke
				(width 0.1524)
				(type default)
			)
			(layer "F.SilkS")
		)
		(fp_line
			(start 0.7874 0.4064)
			(end -0.7874 0.4064)
			(stroke
				(width 0.1524)
				(type default)
			)
			(layer "F.SilkS")
		)
		(fp_line
			(start -0.7874 0.4064)
			(end -0.7874 -0.4064)
			(stroke
				(width 0.1524)
				(type default)
			)
			(layer "F.SilkS")
		)
		(fp_line
			(start -0.12065 -0.305054)
			(end -0.12065 -0.2794)
			(stroke
				(width 0.1)
				(type default)
			)
			(layer "F.Fab")
		)
		(fp_line
			(start -0.67945 -0.305054)
			(end -0.12065 -0.305054)
			(stroke
				(width 0.1)
				(type default)
			)
			(layer "F.Fab")
		)
		(fp_line
			(start 0.67945 -0.3048)
			(end 0.67945 0.3048)
			(stroke
				(width 0.1)
				(type default)
			)
			(layer "F.Fab")
		)
		(fp_line
			(start 0.12065 -0.3048)
			(end 0.67945 -0.3048)
			(stroke
				(width 0.1)
				(type default)
			)
			(layer "F.Fab")
		)
		(fp_line
			(start 0.12065 -0.2794)
			(end 0.12065 -0.3048)
			(stroke
				(width 0.1)
				(type default)
			)
			(layer "F.Fab")
		)
		(fp_line
			(start -0.12065 -0.2794)
			(end 0.12065 -0.2794)
			(stroke
				(width 0.1)
				(type default)
			)
			(layer "F.Fab")
		)
		(fp_line
			(start 0.120396 0.2794)
			(end -0.12065 0.2794)
			(stroke
				(width 0.1)
				(type default)
			)
			(layer "F.Fab")
		)
		(fp_line
			(start -0.12065 0.2794)
			(end -0.12065 0.3048)
			(stroke
				(width 0.1)
				(type default)
			)
			(layer "F.Fab")
		)
		(fp_line
			(start 0.67945 0.3048)
			(end 0.120396 0.3048)
			(stroke
				(width 0.1)
				(type default)
			)
			(layer "F.Fab")
		)
		(fp_line
			(start 0.120396 0.3048)
			(end 0.120396 0.2794)
			(stroke
				(width 0.1)
				(type default)
			)
			(layer "F.Fab")
		)
		(fp_line
			(start -0.12065 0.3048)
			(end -0.67945 0.3048)
			(stroke
				(width 0.1)
				(type default)
			)
			(layer "F.Fab")
		)
		(fp_line
			(start -0.67945 0.3048)
			(end -0.67945 -0.305054)
			(stroke
				(width 0.1)
				(type default)
			)
			(layer "F.Fab")
		)
		(pad "1" smd circle
			(at -0.40005 0 90)
			(size 0 0)
			(layers "F.Cu" "F.Mask" "F.Paste")
			(net "P12V_SSD6")
		)
		(pad "2" smd circle
			(at 0.40005 0 90)
			(size 0 0)
			(layers "F.Cu" "F.Mask" "F.Paste")
			(net "GND")
		)
	)
	(footprint ""
		(layer "F.Cu")
		(at 319.692782 -385.942586)
		(property "Reference" "R6771"
			(at 0 0 0)
			(layer "F.SilkS")
			(hide yes)
			(effects
				(font
					(size 1.27 1.27)
				)
			)
		)
		(property "Value" ""
			(at 0 0 0)
			(layer "F.Fab")
			(effects
				(font
					(size 1.27 1.27)
				)
			)
		)
		(duplicate_pad_numbers_are_jumpers no)
		(fp_line
			(start -0.7874 -0.4064)
			(end 0.7874 -0.4064)
			(stroke
				(width 0.1524)
				(type default)
			)
			(layer "F.SilkS")
		)
		(fp_line
			(start -0.7874 0.4064)
			(end -0.7874 -0.4064)
			(stroke
				(width 0.1524)
				(type default)
			)
			(layer "F.SilkS")
		)
		(fp_line
			(start 0.7874 -0.4064)
			(end 0.7874 0.4064)
			(stroke
				(width 0.1524)
				(type default)
			)
			(layer "F.SilkS")
		)
		(fp_line
			(start 0.7874 0.4064)
			(end -0.7874 0.4064)
			(stroke
				(width 0.1524)
				(type default)
			)
			(layer "F.SilkS")
		)
		(fp_line
			(start -0.67945 -0.305054)
			(end -0.12065 -0.305054)
			(stroke
				(width 0.1)
				(type default)
			)
			(layer "F.Fab")
		)
		(fp_line
			(start -0.67945 0.3048)
			(end -0.67945 -0.305054)
			(stroke
				(width 0.1)
				(type default)
			)
			(layer "F.Fab")
		)
		(fp_line
			(start -0.12065 -0.305054)
			(end -0.12065 -0.2794)
			(stroke
				(width 0.1)
				(type default)
			)
			(layer "F.Fab")
		)
		(fp_line
			(start -0.12065 -0.2794)
			(end 0.12065 -0.2794)
			(stroke
				(width 0.1)
				(type default)
			)
			(layer "F.Fab")
		)
		(fp_line
			(start -0.12065 0.2794)
			(end -0.12065 0.3048)
			(stroke
				(width 0.1)
				(type default)
			)
			(layer "F.Fab")
		)
		(fp_line
			(start -0.12065 0.3048)
			(end -0.67945 0.3048)
			(stroke
				(width 0.1)
				(type default)
			)
			(layer "F.Fab")
		)
		(fp_line
			(start 0.120396 0.2794)
			(end -0.12065 0.2794)
			(stroke
				(width 0.1)
				(type default)
			)
			(layer "F.Fab")
		)
		(fp_line
			(start 0.120396 0.3048)
			(end 0.120396 0.2794)
			(stroke
				(width 0.1)
				(type default)
			)
			(layer "F.Fab")
		)
		(fp_line
			(start 0.12065 -0.3048)
			(end 0.67945 -0.3048)
			(stroke
				(width 0.1)
				(type default)
			)
			(layer "F.Fab")
		)
		(fp_line
			(start 0.12065 -0.2794)
			(end 0.12065 -0.3048)
			(stroke
				(width 0.1)
				(type default)
			)
			(layer "F.Fab")
		)
		(fp_line
			(start 0.67945 -0.3048)
			(end 0.67945 0.3048)
			(stroke
				(width 0.1)
				(type default)
			)
			(layer "F.Fab")
		)
		(fp_line
			(start 0.67945 0.3048)
			(end 0.120396 0.3048)
			(stroke
				(width 0.1)
				(type default)
			)
			(layer "F.Fab")
		)
		(pad "1" smd circle
			(at -0.40005 0)
			(size 0 0)
			(layers "F.Cu" "F.Mask" "F.Paste")
			(net "PRSNT_SWB_B2_N")
		)
		(pad "2" smd circle
			(at 0.40005 0)
			(size 0 0)
			(layers "F.Cu" "F.Mask" "F.Paste")
			(net "GND")
		)
	)
	(footprint ""
		(layer "F.Cu")
		(at 387.62178 -343.952322 90)
		(property "Reference" "C793"
			(at 0 0 90)
			(layer "F.SilkS")
			(hide yes)
			(effects
				(font
					(size 1.27 1.27)
				)
			)
		)
		(property "Value" ""
			(at 0 0 90)
			(layer "F.Fab")
			(effects
				(font
					(size 1.27 1.27)
				)
			)
		)
		(duplicate_pad_numbers_are_jumpers no)
		(fp_line
			(start 0.299974 -0.150114)
			(end 0.299974 0.150114)
			(stroke
				(width 0.1)
				(type default)
			)
			(layer "F.Fab")
		)
		(fp_line
			(start -0.299974 -0.150114)
			(end 0.299974 -0.150114)
			(stroke
				(width 0.1)
				(type default)
			)
			(layer "F.Fab")
		)
		(fp_line
			(start 0.299974 0.150114)
			(end -0.299974 0.150114)
			(stroke
				(width 0.1)
				(type default)
			)
			(layer "F.Fab")
		)
		(fp_line
			(start -0.299974 0.150114)
			(end -0.299974 -0.150114)
			(stroke
				(width 0.1)
				(type default)
			)
			(layer "F.Fab")
		)
		(pad "1" smd rect
			(at -0.2667 0 90)
			(size 0.3048 0.381)
			(layers "F.Cu" "F.Mask" "F.Paste")
			(net "P5E_PEX3_STN6_TX_DN<96>")
		)
		(pad "2" smd rect
			(at 0.2667 0 90)
			(size 0.3048 0.381)
			(layers "F.Cu" "F.Mask" "F.Paste")
			(net "P5E_PEX3_STN6_TX_C_DN<96>")
		)
	)
	(footprint ""
		(layer "F.Cu")
		(at 140.374116 -26.31186 -90)
		(property "Reference" "U402"
			(at -0.10414 -2.324354 90)
			(unlocked yes)
			(layer "F.SilkS")
			(effects
				(font
					(size 0.7874 0.5842)
					(thickness 0.1524)
				)
			)
		)
		(property "Value" ""
			(at 0 0 270)
			(layer "F.Fab")
			(effects
				(font
					(size 1.27 1.27)
				)
			)
		)
		(duplicate_pad_numbers_are_jumpers no)
		(fp_line
			(start -1.949958 1.610106)
			(end -1.949958 -1.610106)
			(stroke
				(width 0.1524)
				(type default)
			)
			(layer "F.SilkS")
		)
		(fp_line
			(start 1.949958 1.610106)
			(end -1.949958 1.610106)
			(stroke
				(width 0.1524)
				(type default)
			)
			(layer "F.SilkS")
		)
		(fp_line
			(start 1.949958 -1.560068)
			(end 1.949958 1.610106)
			(stroke
				(width 0.1524)
				(type default)
			)
			(layer "F.SilkS")
		)
		(fp_line
			(start -1.949958 -1.610106)
			(end 1.949958 -1.610106)
			(stroke
				(width 0.1524)
				(type default)
			)
			(layer "F.SilkS")
		)
		(fp_line
			(start -0.750062 1.560068)
			(end -0.750062 -1.560068)
			(stroke
				(width 0.1)
				(type default)
			)
			(layer "F.Fab")
		)
		(fp_line
			(start 0.750062 1.560068)
			(end -0.750062 1.560068)
			(stroke
				(width 0.1)
				(type default)
			)
			(layer "F.Fab")
		)
		(fp_line
			(start -0.750062 -1.560068)
			(end 0.750062 -1.560068)
			(stroke
				(width 0.1)
				(type default)
			)
			(layer "F.Fab")
		)
		(fp_line
			(start 0.750062 -1.560068)
			(end 0.750062 1.560068)
			(stroke
				(width 0.1)
				(type default)
			)
			(layer "F.Fab")
		)
		(pad "D" smd rect
			(at 1.100074 0 180)
			(size 1.016 1.4224)
			(layers "F.Cu" "F.Mask" "F.Paste")
			(net "SSD4_LED_ISO_N")
		)
		(pad "G" smd rect
			(at -1.100074 -0.94996 180)
			(size 1.016 1.4224)
			(layers "F.Cu" "F.Mask" "F.Paste")
			(net "SSD4_LED_R")
		)
		(pad "S" smd rect
			(at -1.100074 0.94996 180)
			(size 1.016 1.4224)
			(layers "F.Cu" "F.Mask" "F.Paste")
			(net "GND")
		)
	)
	(footprint ""
		(layer "F.Cu")
		(at 97.526602 -55.418228 90)
		(property "Reference" "PC392"
			(at 0 0 90)
			(layer "F.SilkS")
			(hide yes)
			(effects
				(font
					(size 1.27 1.27)
				)
			)
		)
		(property "Value" ""
			(at 0 0 90)
			(layer "F.Fab")
			(effects
				(font
					(size 1.27 1.27)
				)
			)
		)
		(duplicate_pad_numbers_are_jumpers no)
		(fp_line
			(start 0.7874 -0.4064)
			(end 0.7874 0.4064)
			(stroke
				(width 0.1524)
				(type default)
			)
			(layer "F.SilkS")
		)
		(fp_line
			(start -0.7874 -0.4064)
			(end 0.7874 -0.4064)
			(stroke
				(width 0.1524)
				(type default)
			)
			(layer "F.SilkS")
		)
		(fp_line
			(start 0.7874 0.4064)
			(end -0.7874 0.4064)
			(stroke
				(width 0.1524)
				(type default)
			)
			(layer "F.SilkS")
		)
		(fp_line
			(start -0.7874 0.4064)
			(end -0.7874 -0.4064)
			(stroke
				(width 0.1524)
				(type default)
			)
			(layer "F.SilkS")
		)
		(fp_line
			(start -0.12065 -0.305054)
			(end -0.12065 -0.2794)
			(stroke
				(width 0.1)
				(type default)
			)
			(layer "F.Fab")
		)
		(fp_line
			(start -0.67945 -0.305054)
			(end -0.12065 -0.305054)
			(stroke
				(width 0.1)
				(type default)
			)
			(layer "F.Fab")
		)
		(fp_line
			(start 0.67945 -0.3048)
			(end 0.67945 0.3048)
			(stroke
				(width 0.1)
				(type default)
			)
			(layer "F.Fab")
		)
		(fp_line
			(start 0.12065 -0.3048)
			(end 0.67945 -0.3048)
			(stroke
				(width 0.1)
				(type default)
			)
			(layer "F.Fab")
		)
		(fp_line
			(start 0.12065 -0.2794)
			(end 0.12065 -0.3048)
			(stroke
				(width 0.1)
				(type default)
			)
			(layer "F.Fab")
		)
		(fp_line
			(start -0.12065 -0.2794)
			(end 0.12065 -0.2794)
			(stroke
				(width 0.1)
				(type default)
			)
			(layer "F.Fab")
		)
		(fp_line
			(start 0.120396 0.2794)
			(end -0.12065 0.2794)
			(stroke
				(width 0.1)
				(type default)
			)
			(layer "F.Fab")
		)
		(fp_line
			(start -0.12065 0.2794)
			(end -0.12065 0.3048)
			(stroke
				(width 0.1)
				(type default)
			)
			(layer "F.Fab")
		)
		(fp_line
			(start 0.67945 0.3048)
			(end 0.120396 0.3048)
			(stroke
				(width 0.1)
				(type default)
			)
			(layer "F.Fab")
		)
		(fp_line
			(start 0.120396 0.3048)
			(end 0.120396 0.2794)
			(stroke
				(width 0.1)
				(type default)
			)
			(layer "F.Fab")
		)
		(fp_line
			(start -0.12065 0.3048)
			(end -0.67945 0.3048)
			(stroke
				(width 0.1)
				(type default)
			)
			(layer "F.Fab")
		)
		(fp_line
			(start -0.67945 0.3048)
			(end -0.67945 -0.305054)
			(stroke
				(width 0.1)
				(type default)
			)
			(layer "F.Fab")
		)
		(pad "1" smd circle
			(at -0.40005 0 90)
			(size 0 0)
			(layers "F.Cu" "F.Mask" "F.Paste")
			(net "P12V_SSD3_R")
		)
		(pad "2" smd circle
			(at 0.40005 0 90)
			(size 0 0)
			(layers "F.Cu" "F.Mask" "F.Paste")
			(net "GND")
		)
	)
)
